# T6G (Grand Teton) — schematic parts with pin connectivity, parts 2647–2648 of 8303; source: Cadence DE-HDL packaged netlist (pstxprt.dat, pstxnet.dat, pstchip.dat)

J90  SCONN56_123276793  SCONN56_1-2327679-3 IO  pkg CON_F56S2H4D_P0-6W4-6_LUHXA  page 145
  A1  GND_A1  POWER  = GND
  A2  GND_A2  POWER  = GND
  A3  GND_A3  POWER  = GND
  A4  GND_A4  POWER  = GND
  A5  GND_A5  POWER  = GND
  A6  GND_A6  POWER  = GND
  A7  SMBCLK  BI  = SMB_E1S_3V3AUX_ISO_SCL
  A8  SMBDAT  BI  = SMB_E1S_3V3AUX_ISO_SDA
  A9  \smbrst#\  BI  = RST_SMB_E1S_0_N
  A10  \led#_activity\  BI  = FM_LED_ACTIVE_E1S_0_BUF
  A11  \perst1#_clkreq#\  BI  = E1S_0_PERST1_CLKREQ_N
  A12  \prsnt0#\  BI  = E1S_0_PRSNT_N
  A13  GND_A13  POWER  = GND
  A14  REFCLK_N1  BI  = TP_CLK_100M_E1S_0_DN
  A15  REFCLK_P1  BI  = TP_CLK_100M_E1S_0_DP
  A16  GND_A16  POWER  = GND
  A17  PER_N0  BI  = P3E_CPU0_P4_RX_DP<0>
  A18  PER_P0  BI  = P3E_CPU0_P4_RX_DN<0>
  A19  GND_A19  POWER  = GND
  A20  PER_N1  BI  = P3E_CPU0_P4_RX_DP<1>
  A21  PER_P1  BI  = P3E_CPU0_P4_RX_DN<1>
  A22  GND_A22  POWER  = GND
  A23  PER_N2  BI  = P3E_CPU0_P4_RX_DP<2>
  A24  PER_P2  BI  = P3E_CPU0_P4_RX_DN<2>
  A25  GND_A25  POWER  = GND
  A26  PER_N3  BI  = P3E_CPU0_P4_RX_DP<3>
  A27  PER_P3  BI  = P3E_CPU0_P4_RX_DN<3>
  A28  GND_A28  POWER  = GND
  B1  P12V_B1  POWER  = P12V_E1S_0_R
  B2  P12V_B2  POWER  = P12V_E1S_0_R
  B3  P12V_B3  POWER  = P12V_E1S_0_R
  B4  P12V_B4  POWER  = P12V_E1S_0_R
  B5  P12V_B5  POWER  = P12V_E1S_0_R
  B6  P12V_B6  POWER  = P12V_E1S_0_R
  B7  MFG  BI  = TP_E1S_0_MFG
  B8  RFU  BI  = TP_E1S_0_RFU
  B9  \dualporten#\  BI  = PU_E1S_0_DUALPORT_EN_N
  B10  \perst0#\  BI  = RST_PCIE_E1S_PERST_N
  B11  P3V3_AUX  POWER  = P3V3_E1S_0
  B12  PWRDIS  BI  = E1S_0_PWRDIS
  B13  GND_B13  POWER  = GND
  B14  REFCLK_N0  BI  = CLK_100M_CPU0_CLK12_DN
  B15  REFCLK_P0  BI  = CLK_100M_CPU0_CLK12_DP
  B16  GND_B16  POWER  = GND
  B17  PET_N0  BI  = P3E_CPU0_P4_TX_C_DP<0>
  B18  PET_P0  BI  = P3E_CPU0_P4_TX_C_DN<0>
  B19  GND_B19  POWER  = GND
  B20  PET_N1  BI  = P3E_CPU0_P4_TX_C_DP<1>
  B21  PET_P1  BI  = P3E_CPU0_P4_TX_C_DN<1>
  B22  GND_B22  POWER  = GND
  B23  PET_N2  BI  = P3E_CPU0_P4_TX_C_DP<2>
  B24  PET_P2  BI  = P3E_CPU0_P4_TX_C_DN<2>
  B25  GND_B25  POWER  = GND
  B26  PET_N3  BI  = P3E_CPU0_P4_TX_C_DN<3>
  B27  PET_P3  BI  = P3E_CPU0_P4_TX_C_DP<3>
  B28  GND_B28  POWER  = GND
  G1  G1  POWER  = GND
  G2  G2  POWER  = GND

J99  SCONN288_DDR506112002KQ  IO  pkg DDR288S_1-1VXC  page 108
  1  VIN_BULK0  POWER  = P12V_MEM_CPU1
  2  RFU0  TRI  = NC
  3  VIN_MGMT  POWER  = P3V3_AUX
  4  HSCL  IN  = I3C_SPD_DDRK_CPU1_SCL
  5  HSDA  BI  = I3C_SPD_DDRK_CPU1_SDA
  6  VSS0  POWER  = GND
  7  DQ0_A  BI  = M_K_CPU1_SA_DQ<0>
  8  VSS1  POWER  = GND
  9  DQ1_A  BI  = M_K_CPU1_SA_DQ<1>
  10  VSS2  POWER  = GND
  11  DQS0_A_T  BI  = M_K_CPU1_SA_DQS_DP<0>
  12  DQS0_A_C  BI  = M_K_CPU1_SA_DQS_DN<0>
  13  VSS3  POWER  = GND
  14  DQ4_A  BI  = M_K_CPU1_SA_DQ<4>
  15  VSS4  POWER  = GND
  16  DQ5_A  BI  = M_K_CPU1_SA_DQ<5>
  17  VSS5  POWER  = GND
  18  DQ8_A  BI  = M_K_CPU1_SA_DQ<8>
  19  VSS6  POWER  = GND
  20  DQ9_A  BI  = M_K_CPU1_SA_DQ<9>
  21  VSS7  POWER  = GND
  22  DQS1_A_T  BI  = M_K_CPU1_SA_DQS_DP<1>
  23  DQS1_A_C  BI  = M_K_CPU1_SA_DQS_DN<1>
  24  VSS8  POWER  = GND
  25  DQ12_A  BI  = M_K_CPU1_SA_DQ<12>
  26  VSS9  POWER  = GND
  27  DQ13_A  BI  = M_K_CPU1_SA_DQ<13>
  28  VSS10  POWER  = GND
  29  DQ16_A  BI  = M_K_CPU1_SA_DQ<16>
  30  VSS11  POWER  = GND
  31  DQ17_A  BI  = M_K_CPU1_SA_DQ<17>
  32  VSS12  POWER  = GND
  33  DQS2_A_T  BI  = M_K_CPU1_SA_DQS_DP<2>
  34  DQS2_A_C  BI  = M_K_CPU1_SA_DQS_DN<2>
  35  VSS13  POWER  = GND
  36  DQ20_A  BI  = M_K_CPU1_SA_DQ<20>
  37  VSS14  POWER  = GND
  38  DQ21_A  BI  = M_K_CPU1_SA_DQ<21>
  39  VSS15  POWER  = GND
  40  DQ24_A  BI  = M_K_CPU1_SA_DQ<24>
  41  VSS16  POWER  = GND
  42  DQ25_A  BI  = M_K_CPU1_SA_DQ<25>
  43  VSS17  POWER  = GND
  44  DQS3_A_T  BI  = M_K_CPU1_SA_DQS_DP<3>
  45  DQS3_A_C  BI  = M_K_CPU1_SA_DQS_DN<3>
  46  VSS18  POWER  = GND
  47  DQ28_A  BI  = M_K_CPU1_SA_DQ<28>
  48  VSS19  POWER  = GND
  49  DQ29_A  BI  = M_K_CPU1_SA_DQ<29>
  50  VSS20  POWER  = GND
  51  CB0_A  BI  = M_K_CPU1_SA_CB<0>
  52  VSS21  POWER  = GND
  53  CB1_A  BI  = M_K_CPU1_SA_CB<1>
  54  VSS22  POWER  = GND
  55  DQS4_A_T  BI  = M_K_CPU1_SA_DQS_DP<4>
  56  DQS4_A_C  BI  = M_K_CPU1_SA_DQS_DN<4>
  57  VSS23  POWER  = GND
  58  CB4_A  BI  = M_K_CPU1_SA_CB<4>
  59  VSS24  POWER  = GND
  60  CB5_A  BI  = M_K_CPU1_SA_CB<5>
  61  VSS25  POWER  = GND
  62  ALERT_N  OUT  = M_K_CPU1_ALERT_N
  63  VSS26  POWER  = GND
  64  CS0_A_N  IN  = M_K_CPU1_SA_CS_N<0>
  65  VSS27  POWER  = GND
  66  CA0_A  IN  = M_K_CPU1_SA_CA<0>
  67  VSS28  POWER  = GND
  68  CA2_A  IN  = M_K_CPU1_SA_CA<2>
  69  VSS29  POWER  = GND
  70  CA4_A  IN  = M_K_CPU1_SA_CA<4>
  71  VSS30  POWER  = GND
  72  CA6_A  IN  = M_K_CPU1_SA_CA<6>
  73  VSS31  POWER  = GND
  74  PAR_A  IN  = M_K_CPU1_SA_PAR
  75  VSS32  POWER  = GND
  76  CA0_B  IN  = M_K_CPU1_SB_CA<0>
  77  VSS33  POWER  = GND
  78  CA2_B  IN  = M_K_CPU1_SB_CA<2>
  79  VSS34  POWER  = GND
  80  CA4_B  IN  = M_K_CPU1_SB_CA<4>
  81  VSS35  POWER  = GND
  82  CA6_B  IN  = M_K_CPU1_SB_CA<6>
  83  VSS36  POWER  = GND
  84  CS0_B_N  IN  = M_K_CPU1_SB_CS_N<0>
  85  VSS37  POWER  = GND
  86  \lbd||rsp_a_n\  OUT  = M_K_CPU1_SA_RSP<0>
  87  \lbs||rsp_b_n\  OUT  = M_K_CPU1_SB_RSP<0>
  88  VSS38  POWER  = GND
  89  CB4_B  BI  = M_K_CPU1_SB_CB<4>
  90  VSS39  POWER  = GND
  91  CB5_B  BI  = M_K_CPU1_SB_CB<5>
  92  VSS40  POWER  = GND
  93  \dqs9_b_t||tdqs9_b_t||dbi4_b_n\  BI  = M_K_CPU1_SB_DQS_DP<9>
  94  \dqs9_b_c||tdqs9_b_c\  BI  = M_K_CPU1_SB_DQS_DN<9>
  95  VSS41  POWER  = GND
  96  CB0_B  BI  = M_K_CPU1_SB_CB<0>
  97  VSS42  POWER  = GND
  98  CB1_B  BI  = M_K_CPU1_SB_CB<1>
  99  VSS43  POWER  = GND
  100  DQ0_B  BI  = M_K_CPU1_SB_DQ<0>
  101  VSS44  POWER  = GND
  102  DQ1_B  BI  = M_K_CPU1_SB_DQ<1>
  103  VSS45  POWER  = GND
  104  DQS0_B_T  BI  = M_K_CPU1_SB_DQS_DP<0>
  105  DQS0_B_C  BI  = M_K_CPU1_SB_DQS_DN<0>
  106  VSS46  POWER  = GND
  107  DQ4_B  BI  = M_K_CPU1_SB_DQ<4>
  108  VSS47  POWER  = GND
  109  DQ5_B  BI  = M_K_CPU1_SB_DQ<5>
  110  VSS48  POWER  = GND
  111  DQ8_B  BI  = M_K_CPU1_SB_DQ<8>
  112  VSS49  POWER  = GND
  113  DQ9_B  BI  = M_K_CPU1_SB_DQ<9>
  114  VSS50  POWER  = GND
  115  DQS1_B_T  BI  = M_K_CPU1_SB_DQS_DP<1>
  116  DQS1_B_C  BI  = M_K_CPU1_SB_DQS_DN<1>
  117  VSS51  POWER  = GND
  118  DQ12_B  BI  = M_K_CPU1_SB_DQ<12>
  119  VSS52  POWER  = GND
  120  DQ13_B  BI  = M_K_CPU1_SB_DQ<13>
  121  VSS53  POWER  = GND
  122  DQ16_B  BI  = M_K_CPU1_SB_DQ<16>
  123  VSS54  POWER  = GND
  124  DQ17_B  BI  = M_K_CPU1_SB_DQ<17>
  125  VSS55  POWER  = GND
  126  DQS2_B_T  BI  = M_K_CPU1_SB_DQS_DP<2>
  127  DQS2_B_C  BI  = M_K_CPU1_SB_DQS_DN<2>
  128  VSS56  POWER  = GND
  129  DQ20_B  BI  = M_K_CPU1_SB_DQ<20>
  130  VSS57  POWER  = GND
  131  DQ21_B  BI  = M_K_CPU1_SB_DQ<21>
  132  VSS58  POWER  = GND
  133  DQ24_B  BI  = M_K_CPU1_SB_DQ<24>
  134  VSS59  POWER  = GND
  135  DQ25_B  BI  = M_K_CPU1_SB_DQ<25>
  136  VSS60  POWER  = GND
  137  DQS3_B_T  BI  = M_K_CPU1_SB_DQS_DP<3>
  138  DQS3_B_C  BI  = M_K_CPU1_SB_DQS_DN<3>
  139  VSS61  POWER  = GND
  140  DQ28_B  BI  = M_K_CPU1_SB_DQ<28>
  141  VSS62  POWER  = GND
  142  DQ29_B  BI  = M_K_CPU1_SB_DQ<29>
  143  VSS63  POWER  = GND
  144  RFU1  TRI  = NC
  145  VIN_BULK1  POWER  = P12V_MEM_CPU1
  146  VIN_BULK2  POWER  = P12V_MEM_CPU1
  147  \pwr_good||fail_n\  BI  = PWRGD_CHK_CPU1_DIMM
  148  HAS  IN  = PD_CHK_CPU1_DIMM_SAA
  149  RFU2  TRI  = NC
  150  RFU3  TRI  = NC
  151  VSS64  POWER  = GND
  152  DQ2_A  BI  = M_K_CPU1_SA_DQ<2>
  153  VSS65  POWER  = GND
  154  DQ3_A  BI  = M_K_CPU1_SA_DQ<3>
  155  VSS66  POWER  = GND
  156  \dqs5_a_c||tdqs5_a_c||dqs5_a_t||tdqs5_a_t\  BI  = M_K_CPU1_SA_DQS_DN<5>
  157  \dqs5_a_t||tdqs5_a_t\  BI  = M_K_CPU1_SA_DQS_DP<5>
  158  VSS67  POWER  = GND
  159  DQ6_A  BI  = M_K_CPU1_SA_DQ<6>
  160  VSS68  POWER  = GND
  161  DQ7_A  BI  = M_K_CPU1_SA_DQ<7>
  162  VSS69  POWER  = GND
  163  DQ10_A  BI  = M_K_CPU1_SA_DQ<10>
  164  VSS70  POWER  = GND
  165  DQ11_A  BI  = M_K_CPU1_SA_DQ<11>
  166  VSS71  POWER  = GND
  167  \dqs6_a_c||tdqs6_a_c||dqs6_a_t||tdqs6_a_t\  BI  = M_K_CPU1_SA_DQS_DN<6>
  168  \dqs6_a_t||tdqs6_a_t\  BI  = M_K_CPU1_SA_DQS_DP<6>
  169  VSS72  POWER  = GND
  170  DQ14_A  BI  = M_K_CPU1_SA_DQ<14>
  171  VSS73  POWER  = GND
  172  DQ15_A  BI  = M_K_CPU1_SA_DQ<15>
  173  VSS74  POWER  = GND
  174  DQ18_A  BI  = M_K_CPU1_SA_DQ<18>
  175  VSS75  POWER  = GND
  176  DQ19_A  BI  = M_K_CPU1_SA_DQ<19>
  177  VSS76  POWER  = GND
  178  \dqs7_a_c||tdqs7_a_c\  BI  = M_K_CPU1_SA_DQS_DN<7>
  179  \dqs7_a_t||tdqs7_a_t\  BI  = M_K_CPU1_SA_DQS_DP<7>
  180  VSS77  POWER  = GND
  181  DQ22_A  BI  = M_K_CPU1_SA_DQ<22>
  182  VSS78  POWER  = GND
  183  DQ23_A  BI  = M_K_CPU1_SA_DQ<23>
  184  VSS79  POWER  = GND
  185  DQ26_A  BI  = M_K_CPU1_SA_DQ<26>
  186  VSS80  POWER  = GND
  187  DQ27_A  BI  = M_K_CPU1_SA_DQ<27>
  188  VSS81  POWER  = GND
  189  \dqs8_a_c||tdqs8_a_c\  BI  = M_K_CPU1_SA_DQS_DN<8>
  190  \dqs8_a_t||tdqs8_a_t\  BI  = M_K_CPU1_SA_DQS_DP<8>
  191  VSS82  POWER  = GND
  192  DQ30_A  BI  = M_K_CPU1_SA_DQ<30>
  193  VSS83  POWER  = GND
  194  DQ31_A  BI  = M_K_CPU1_SA_DQ<31>
  195  VSS84  POWER  = GND
  196  CB2_A  BI  = M_K_CPU1_SA_CB<2>
  197  VSS85  POWER  = GND
  198  CB3_A  BI  = M_K_CPU1_SA_CB<3>
  199  VSS86  POWER  = GND
  200  \dqs9_a_c||tdqs9_a_c\  BI  = M_K_CPU1_SA_DQS_DN<9>
  201  \dqs9_a_t||tdqs9_a_t\  BI  = M_K_CPU1_SA_DQS_DP<9>
  202  VSS87  POWER  = GND
  203  CB6_A  BI  = M_K_CPU1_SA_CB<6>
  204  VSS88  POWER  = GND
  205  CB7_A  BI  = M_K_CPU1_SA_CB<7>
  206  VSS89  POWER  = GND
  207  RESET_N  IN  = M_K_CPU1_RESET_N
  208  VSS90  POWER  = GND
  209  CS1_A_N  IN  = M_K_CPU1_SA_CS_N<1>
  210  VSS91  POWER  = GND
  211  CA1_A  IN  = M_K_CPU1_SA_CA<1>
  212  VSS92  POWER  = GND
  213  CA3_A  IN  = M_K_CPU1_SA_CA<3>
  214  VSS93  POWER  = GND
  215  CA5_A  IN  = M_K_CPU1_SA_CA<5>
  216  VSS94  POWER  = GND
  217  CK_T  IN  = M_K_CPU1_CLK_DP<0>
  218  CK_C  IN  = M_K_CPU1_CLK_DN<0>
  219  VSS95  POWER  = GND
  220  RFU4  TRI  = NC
  221  CA1_B  IN  = M_K_CPU1_SB_CA<1>
  222  VSS96  POWER  = GND
  223  CA3_B  IN  = M_K_CPU1_SB_CA<3>
  224  VSS97  POWER  = GND
  225  CA5_B  IN  = M_K_CPU1_SB_CA<5>
  226  VSS98  POWER  = GND
  227  PAR_B  IN  = M_K_CPU1_SB_PAR
  228  VSS99  POWER  = GND
  229  CS1_B_N  IN  = M_K_CPU1_SB_CS_N<1>
  230  VSS100  POWER  = GND
  231  RFU5  TRI  = NC
  232  RFU6  TRI  = NC
  233  VSS101  POWER  = GND
  234  CB6_B  BI  = M_K_CPU1_SB_CB<6>
  235  VSS102  POWER  = GND
  236  CB7_B  BI  = M_K_CPU1_SB_CB<7>
  237  VSS103  POWER  = GND
  238  DQS4_B_C  BI  = M_K_CPU1_SB_DQS_DN<4>
  239  DQS4_B_T  BI  = M_K_CPU1_SB_DQS_DP<4>
  240  VSS104  POWER  = GND
  241  CB2_B  BI  = M_K_CPU1_SB_CB<2>
  242  VSS105  POWER  = GND
  243  CB3_B  BI  = M_K_CPU1_SB_CB<3>
  244  VSS106  POWER  = GND
  245  DQ2_B  BI  = M_K_CPU1_SB_DQ<2>
  246  VSS107  POWER  = GND
  247  DQ3_B  BI  = M_K_CPU1_SB_DQ<3>
  248  VSS108  POWER  = GND
  249  \dqs5_b_c||tdqs5_b_c\  BI  = M_K_CPU1_SB_DQS_DN<5>
  250  \dqs5_b_t||tdqs5_b_t\  BI  = M_K_CPU1_SB_DQS_DP<5>
  251  VSS109  POWER  = GND
  252  DQ6_B  BI  = M_K_CPU1_SB_DQ<6>
  253  VSS110  POWER  = GND
  254  DQ7_B  BI  = M_K_CPU1_SB_DQ<7>
  255  VSS111  POWER  = GND
  256  DQ10_B  BI  = M_K_CPU1_SB_DQ<10>
  257  VSS112  POWER  = GND
  258  DQ11_B  BI  = M_K_CPU1_SB_DQ<11>
  259  VSS113  POWER  = GND
  260  \dqs6_b_c||tdqs6_b_c\  BI  = M_K_CPU1_SB_DQS_DN<6>
  261  \dqs6_b_t||tdqs6_b_t\  BI  = M_K_CPU1_SB_DQS_DP<6>
  262  VSS114  POWER  = GND
  263  DQ14_B  BI  = M_K_CPU1_SB_DQ<14>
  264  VSS115  POWER  = GND
  265  DQ15_B  BI  = M_K_CPU1_SB_DQ<15>
  266  VSS116  POWER  = GND
  267  DQ18_B  BI  = M_K_CPU1_SB_DQ<18>
  268  VSS117  POWER  = GND
  269  DQ19_B  BI  = M_K_CPU1_SB_DQ<19>
  270  VSS118  POWER  = GND
  271  \dqs7_b_c||tdqs7_b_c\  BI  = M_K_CPU1_SB_DQS_DN<7>
  272  \dqs7_b_t||tdqs7_b_t\  BI  = M_K_CPU1_SB_DQS_DP<7>
  273  VSS119  POWER  = GND
  274  DQ22_B  BI  = M_K_CPU1_SB_DQ<22>
  275  VSS120  POWER  = GND
  276  DQ23_B  BI  = M_K_CPU1_SB_DQ<23>
  277  VSS121  POWER  = GND
  278  DQ26_B  BI  = M_K_CPU1_SB_DQ<26>
  279  VSS122  POWER  = GND
  280  DQ27_B  BI  = M_K_CPU1_SB_DQ<27>
  281  VSS123  POWER  = GND
  282  \dqs8_b_c||tdqs8_b_c\  BI  = M_K_CPU1_SB_DQS_DN<8>
  283  \dqs8_b_t||tdqs8_b_t\  BI  = M_K_CPU1_SB_DQS_DP<8>
  284  VSS124  POWER  = GND
  285  DQ30_B  BI  = M_K_CPU1_SB_DQ<30>
  286  VSS125  POWER  = GND
  287  DQ31_B  BI  = M_K_CPU1_SB_DQ<31>
  288  VSS126  POWER  = GND
  G1  G1  POWER  = GND
  G2  G2  POWER  = GND
  G3  G3  POWER  = GND
